# S9S_MB_2U (Grand Teton) — schematic netlist excerpt (pin names and nets, part order shuffled) for the footprints in the layout excerpt that follows; sources: Cadence DE-HDL packaged netlist, KiCad conversion of 03242023_DA0F0TMBIJ0_F0T_Motherboard_J_brd_V01_OCP.brd

R3193  Q_RES  33.2 1% CHIP  pkg 0402LF  page 161 : A = IRQ_LVC3_V3_2_WAKE_BUF_N ; B = IRQ_LVC3_WAKE_N
C1098  Q_CAP_DIFFBUS  DIFF BUS_0.22UF 6.3V 20% X6S  pkg C0201  page 181 : \1\ = P3E_PCH_M2_TX_DP<3> ; \2\ = P3E_PCH_M2_TX_C_DP<3>

(kicad_pcb
	(version 20260206)
	(generator "pcbnew")
	(generator_version "10.0")
	(general
		(thickness 1.6)
		(legacy_teardrops no)
	)
	(paper "A4")
	(title_block
		(title "03242023_DA0F0TMBIJ0_F0T_Motherboard_J_brd_V01_OCP.brd")
		(comment 1 "Grand Teton / footprints 1092-1093 of 6105")
	)
	(layers
		(0 "F.Cu" signal "TOP")
		(4 "In1.Cu" signal "GND")
		(6 "In2.Cu" signal "IN1")
		(8 "In3.Cu" signal "GND1")
		(10 "In4.Cu" signal "IN2")
		(12 "In5.Cu" signal "GND2")
		(14 "In6.Cu" signal "IN3")
		(16 "In7.Cu" signal "GND3")
		(18 "In8.Cu" signal "VCC")
		(20 "In9.Cu" signal "VCC1")
		(22 "In10.Cu" signal "GND4")
		(24 "In11.Cu" signal "IN4")
		(26 "In12.Cu" signal "GND5")
		(28 "In13.Cu" signal "IN5")
		(30 "In14.Cu" signal "GND6")
		(32 "In15.Cu" signal "IN6")
		(34 "In16.Cu" signal "GND7")
		(2 "B.Cu" signal "BOTTOM")
		(9 "F.Adhes" user "F.Adhesive")
		(11 "B.Adhes" user "B.Adhesive")
		(13 "F.Paste" user "Package Geometry/Pastemask Top")
		(15 "B.Paste" user "Package Geometry/Pastemask Bottom")
		(5 "F.SilkS" user "Ref Des/Silkscreen Top")
		(7 "B.SilkS" user "Ref Des/Silkscreen Bottom")
		(1 "F.Mask" user "Board Geometry/Soldermask Top")
		(3 "B.Mask" user "Board Geometry/Soldermask Bottom")
		(17 "Dwgs.User" user "User.Drawings")
		(19 "Cmts.User" user "User.Comments")
		(21 "Eco1.User" user "User.Eco1")
		(23 "Eco2.User" user "User.Eco2")
		(25 "Edge.Cuts" user "Board Geometry/Outline")
		(27 "Margin" user)
		(31 "F.CrtYd" user "Package Geometry/Place Bound Top")
		(29 "B.CrtYd" user "Package Geometry/Place Bound Bottom")
		(35 "F.Fab" user "Ref Des/Assembly Top")
		(33 "B.Fab" user "Ref Des/Assembly Bottom")
	)
	(footprint ""
		(layer "F.Cu")
		(at 280.830528 -14.09827)
		(property "Reference" "R3193"
			(at 0 0 0)
			(layer "F.SilkS")
			(hide yes)
			(effects
				(font
					(size 1.27 1.27)
				)
			)
		)
		(property "Value" ""
			(at 0 0 0)
			(layer "F.Fab")
			(effects
				(font
					(size 1.27 1.27)
				)
			)
		)
		(duplicate_pad_numbers_are_jumpers no)
		(fp_line
			(start -0.7874 -0.4064)
			(end 0.7874 -0.4064)
			(stroke
				(width 0.1524)
				(type default)
			)
			(layer "F.SilkS")
		)
		(fp_line
			(start -0.7874 0.4064)
			(end -0.7874 -0.4064)
			(stroke
				(width 0.1524)
				(type default)
			)
			(layer "F.SilkS")
		)
		(fp_line
			(start 0.7874 -0.4064)
			(end 0.7874 0.4064)
			(stroke
				(width 0.1524)
				(type default)
			)
			(layer "F.SilkS")
		)
		(fp_line
			(start 0.7874 0.4064)
			(end -0.7874 0.4064)
			(stroke
				(width 0.1524)
				(type default)
			)
			(layer "F.SilkS")
		)
		(fp_line
			(start -0.67945 -0.305054)
			(end -0.12065 -0.305054)
			(stroke
				(width 0.1)
				(type default)
			)
			(layer "F.Fab")
		)
		(fp_line
			(start -0.67945 0.3048)
			(end -0.67945 -0.305054)
			(stroke
				(width 0.1)
				(type default)
			)
			(layer "F.Fab")
		)
		(fp_line
			(start -0.12065 -0.305054)
			(end -0.12065 -0.2794)
			(stroke
				(width 0.1)
				(type default)
			)
			(layer "F.Fab")
		)
		(fp_line
			(start -0.12065 -0.2794)
			(end 0.12065 -0.2794)
			(stroke
				(width 0.1)
				(type default)
			)
			(layer "F.Fab")
		)
		(fp_line
			(start -0.12065 0.2794)
			(end -0.12065 0.3048)
			(stroke
				(width 0.1)
				(type default)
			)
			(layer "F.Fab")
		)
		(fp_line
			(start -0.12065 0.3048)
			(end -0.67945 0.3048)
			(stroke
				(width 0.1)
				(type default)
			)
			(layer "F.Fab")
		)
		(fp_line
			(start 0.120396 0.2794)
			(end -0.12065 0.2794)
			(stroke
				(width 0.1)
				(type default)
			)
			(layer "F.Fab")
		)
		(fp_line
			(start 0.120396 0.3048)
			(end 0.120396 0.2794)
			(stroke
				(width 0.1)
				(type default)
			)
			(layer "F.Fab")
		)
		(fp_line
			(start 0.12065 -0.3048)
			(end 0.67945 -0.3048)
			(stroke
				(width 0.1)
				(type default)
			)
			(layer "F.Fab")
		)
		(fp_line
			(start 0.12065 -0.2794)
			(end 0.12065 -0.3048)
			(stroke
				(width 0.1)
				(type default)
			)
			(layer "F.Fab")
		)
		(fp_line
			(start 0.67945 -0.3048)
			(end 0.67945 0.3048)
			(stroke
				(width 0.1)
				(type default)
			)
			(layer "F.Fab")
		)
		(fp_line
			(start 0.67945 0.3048)
			(end 0.120396 0.3048)
			(stroke
				(width 0.1)
				(type default)
			)
			(layer "F.Fab")
		)
		(pad "1" smd circle
			(at -0.40005 0)
			(size 0 0)
			(layers "F.Cu" "F.Mask" "F.Paste")
			(net "IRQ_LVC3_V3_2_WAKE_BUF_N")
		)
		(pad "2" smd circle
			(at 0.40005 0)
			(size 0 0)
			(layers "F.Cu" "F.Mask" "F.Paste")
			(net "IRQ_LVC3_WAKE_N")
		)
	)
	(footprint ""
		(layer "F.Cu")
		(at 180.528468 -45.005498 180)
		(property "Reference" "C1098"
			(at 0 0 180)
			(layer "F.SilkS")
			(hide yes)
			(effects
				(font
					(size 1.27 1.27)
				)
			)
		)
		(property "Value" ""
			(at 0 0 180)
			(layer "F.Fab")
			(effects
				(font
					(size 1.27 1.27)
				)
			)
		)
		(duplicate_pad_numbers_are_jumpers no)
		(fp_line
			(start 0.299974 0.150114)
			(end -0.299974 0.150114)
			(stroke
				(width 0.1)
				(type default)
			)
			(layer "F.Fab")
		)
		(fp_line
			(start 0.299974 -0.150114)
			(end 0.299974 0.150114)
			(stroke
				(width 0.1)
				(type default)
			)
			(layer "F.Fab")
		)
		(fp_line
			(start -0.299974 0.150114)
			(end -0.299974 -0.150114)
			(stroke
				(width 0.1)
				(type default)
			)
			(layer "F.Fab")
		)
		(fp_line
			(start -0.299974 -0.150114)
			(end 0.299974 -0.150114)
			(stroke
				(width 0.1)
				(type default)
			)
			(layer "F.Fab")
		)
		(pad "1" smd rect
			(at -0.2667 0 180)
			(size 0.3048 0.381)
			(layers "F.Cu" "F.Mask" "F.Paste")
			(net "P3E_PCH_M2_TX_DP<3>")
		)
		(pad "2" smd rect
			(at 0.2667 0 180)
			(size 0.3048 0.381)
			(layers "F.Cu" "F.Mask" "F.Paste")
			(net "P3E_PCH_M2_TX_C_DP<3>")
		)
		(zone
			(layer "In1.Cu")
			(hatch none 0.5)
			(connect_pads
				(clearance 0)
			)
			(min_thickness 0.25)
			(keepout
				(tracks not_allowed)
				(vias allowed)
				(pads allowed)
				(copperpour not_allowed)
				(footprints allowed)
			)
			(placement
				(enabled no)
				(sheetname "")
			)
			(fill
				(thermal_gap 0.5)
				(thermal_bridge_width 0.5)
				(island_removal_mode 0)
			)
			(polygon
				(pts
					(arc
						(start 180.388768 -45.246798)
						(mid 180.44265 -45.22448)
						(end 180.464968 -45.170598)
					)
					(arc
						(start 180.464968 -44.840398)
						(mid 180.44265 -44.786516)
						(end 180.388768 -44.764198)
					)
					(arc
						(start 180.134768 -44.764198)
						(mid 180.080886 -44.786516)
						(end 180.058568 -44.840398)
					)
					(arc
						(start 180.058568 -45.170598)
						(mid 180.080886 -45.22448)
						(end 180.134768 -45.246798)
					)
				)
			)
		)
		(zone
			(layer "In1.Cu")
			(hatch none 0.5)
			(connect_pads
				(clearance 0)
			)
			(min_thickness 0.25)
			(keepout
				(tracks not_allowed)
				(vias allowed)
				(pads allowed)
				(copperpour not_allowed)
				(footprints allowed)
			)
			(placement
				(enabled no)
				(sheetname "")
			)
			(fill
				(thermal_gap 0.5)
				(thermal_bridge_width 0.5)
				(island_removal_mode 0)
			)
			(polygon
				(pts
					(arc
						(start 180.922168 -45.246798)
						(mid 180.97605 -45.22448)
						(end 180.998368 -45.170598)
					)
					(arc
						(start 180.998368 -44.840398)
						(mid 180.97605 -44.786516)
						(end 180.922168 -44.764198)
					)
					(arc
						(start 180.668168 -44.764198)
						(mid 180.614286 -44.786516)
						(end 180.591968 -44.840398)
					)
					(arc
						(start 180.591968 -45.170598)
						(mid 180.614286 -45.22448)
						(end 180.668168 -45.246798)
					)
				)
			)
		)
	)
)
